(kicad_pcb
	(version 20260206)
	(generator "pcbnew")
	(generator_version "10.0")
	(general
		(thickness 1.6)
		(legacy_teardrops no)
	)
	(paper "A4")
	(title_block
		(title "04192023_DAF0TMB3IC0_F0TG_MB_C_brd_V02_OCP.brd")
		(comment 1 "Grand Teton / footprints 6433-6439 of 8354")
	)
	(layers
		(0 "F.Cu" signal "TOP")
		(4 "In1.Cu" signal "GND")
		(6 "In2.Cu" signal "IN1")
		(8 "In3.Cu" signal "GND1")
		(10 "In4.Cu" signal "IN2")
		(12 "In5.Cu" signal "GND2")
		(14 "In6.Cu" signal "IN3")
		(16 "In7.Cu" signal "GND3")
		(18 "In8.Cu" signal "VCC")
		(20 "In9.Cu" signal "VCC1")
		(22 "In10.Cu" signal "GND4")
		(24 "In11.Cu" signal "IN4")
		(26 "In12.Cu" signal "GND5")
		(28 "In13.Cu" signal "IN5")
		(30 "In14.Cu" signal "GND6")
		(32 "In15.Cu" signal "IN6")
		(34 "In16.Cu" signal "GND7")
		(2 "B.Cu" signal "BOTTOM")
		(9 "F.Adhes" user "F.Adhesive")
		(11 "B.Adhes" user "B.Adhesive")
		(13 "F.Paste" user "Package Geometry/Pastemask Top")
		(15 "B.Paste" user "Package Geometry/Pastemask Bottom")
		(5 "F.SilkS" user "Ref Des/Silkscreen Top")
		(7 "B.SilkS" user "Ref Des/Silkscreen Bottom")
		(1 "F.Mask" user "Board Geometry/Soldermask Top")
		(3 "B.Mask" user "Board Geometry/Soldermask Bottom")
		(17 "Dwgs.User" user "User.Drawings")
		(19 "Cmts.User" user "User.Comments")
		(21 "Eco1.User" user "User.Eco1")
		(23 "Eco2.User" user "User.Eco2")
		(25 "Edge.Cuts" user "Board Geometry/Outline")
		(27 "Margin" user)
		(31 "F.CrtYd" user "Package Geometry/Place Bound Top")
		(29 "B.CrtYd" user "Package Geometry/Place Bound Bottom")
		(35 "F.Fab" user "Ref Des/Assembly Top")
		(33 "B.Fab" user "Ref Des/Assembly Bottom")
	)
	(footprint ""
		(layer "B.Cu")
		(at 342.923876 -66.708782 90)
		(property "Reference" "R3095"
			(at 0 0 90)
			(layer "B.SilkS")
			(hide yes)
			(effects
				(font
					(size 1.27 1.27)
				)
				(justify mirror)
			)
		)
		(property "Value" ""
			(at 0 0 90)
			(layer "B.Fab")
			(effects
				(font
					(size 1.27 1.27)
				)
				(justify mirror)
			)
		)
		(duplicate_pad_numbers_are_jumpers no)
		(fp_line
			(start 0.7874 -0.4064)
			(end -0.7874 -0.4064)
			(stroke
				(width 0.1524)
				(type default)
			)
			(layer "B.SilkS")
		)
		(fp_line
			(start -0.7874 -0.4064)
			(end -0.7874 0.4064)
			(stroke
				(width 0.1524)
				(type default)
			)
			(layer "B.SilkS")
		)
		(fp_line
			(start 0.7874 0.4064)
			(end 0.7874 -0.4064)
			(stroke
				(width 0.1524)
				(type default)
			)
			(layer "B.SilkS")
		)
		(fp_line
			(start -0.7874 0.4064)
			(end 0.7874 0.4064)
			(stroke
				(width 0.1524)
				(type default)
			)
			(layer "B.SilkS")
		)
		(fp_line
			(start 0.67945 -0.305054)
			(end 0.12065 -0.305054)
			(stroke
				(width 0.1)
				(type default)
			)
			(layer "B.Fab")
		)
		(fp_line
			(start 0.12065 -0.305054)
			(end 0.12065 -0.2794)
			(stroke
				(width 0.1)
				(type default)
			)
			(layer "B.Fab")
		)
		(fp_line
			(start -0.12065 -0.3048)
			(end -0.67945 -0.3048)
			(stroke
				(width 0.1)
				(type default)
			)
			(layer "B.Fab")
		)
		(fp_line
			(start -0.67945 -0.3048)
			(end -0.67945 0.3048)
			(stroke
				(width 0.1)
				(type default)
			)
			(layer "B.Fab")
		)
		(fp_line
			(start 0.12065 -0.2794)
			(end -0.12065 -0.2794)
			(stroke
				(width 0.1)
				(type default)
			)
			(layer "B.Fab")
		)
		(fp_line
			(start -0.12065 -0.2794)
			(end -0.12065 -0.3048)
			(stroke
				(width 0.1)
				(type default)
			)
			(layer "B.Fab")
		)
		(fp_line
			(start 0.12065 0.2794)
			(end 0.12065 0.3048)
			(stroke
				(width 0.1)
				(type default)
			)
			(layer "B.Fab")
		)
		(fp_line
			(start -0.120396 0.2794)
			(end 0.12065 0.2794)
			(stroke
				(width 0.1)
				(type default)
			)
			(layer "B.Fab")
		)
		(fp_line
			(start 0.67945 0.3048)
			(end 0.67945 -0.305054)
			(stroke
				(width 0.1)
				(type default)
			)
			(layer "B.Fab")
		)
		(fp_line
			(start 0.12065 0.3048)
			(end 0.67945 0.3048)
			(stroke
				(width 0.1)
				(type default)
			)
			(layer "B.Fab")
		)
		(fp_line
			(start -0.120396 0.3048)
			(end -0.120396 0.2794)
			(stroke
				(width 0.1)
				(type default)
			)
			(layer "B.Fab")
		)
		(fp_line
			(start -0.67945 0.3048)
			(end -0.120396 0.3048)
			(stroke
				(width 0.1)
				(type default)
			)
			(layer "B.Fab")
		)
		(pad "1" smd circle
			(at 0.40005 0 270)
			(size 0 0)
			(layers "B.Cu" "B.Mask" "B.Paste")
			(net "LED_PWRGD_PVDDIO_P1_R")
		)
		(pad "2" smd circle
			(at -0.40005 0 270)
			(size 0 0)
			(layers "B.Cu" "B.Mask" "B.Paste")
			(net "P3V3_AUX")
		)
	)
	(footprint ""
		(layer "B.Cu")
		(at 287.986978 -419.04285)
		(property "Reference" "C79"
			(at 0 0 0)
			(layer "B.SilkS")
			(hide yes)
			(effects
				(font
					(size 1.27 1.27)
				)
				(justify mirror)
			)
		)
		(property "Value" ""
			(at 0 0 0)
			(layer "B.Fab")
			(effects
				(font
					(size 1.27 1.27)
				)
				(justify mirror)
			)
		)
		(duplicate_pad_numbers_are_jumpers no)
		(fp_line
			(start -0.7874 -0.4064)
			(end -0.7874 0.4064)
			(stroke
				(width 0.1524)
				(type default)
			)
			(layer "B.SilkS")
		)
		(fp_line
			(start -0.7874 0.4064)
			(end 0.7874 0.4064)
			(stroke
				(width 0.1524)
				(type default)
			)
			(layer "B.SilkS")
		)
		(fp_line
			(start 0.7874 -0.4064)
			(end -0.7874 -0.4064)
			(stroke
				(width 0.1524)
				(type default)
			)
			(layer "B.SilkS")
		)
		(fp_line
			(start 0.7874 0.4064)
			(end 0.7874 -0.4064)
			(stroke
				(width 0.1524)
				(type default)
			)
			(layer "B.SilkS")
		)
		(fp_line
			(start -0.67945 -0.3048)
			(end -0.67945 0.3048)
			(stroke
				(width 0.1)
				(type default)
			)
			(layer "B.Fab")
		)
		(fp_line
			(start -0.67945 0.3048)
			(end -0.120396 0.3048)
			(stroke
				(width 0.1)
				(type default)
			)
			(layer "B.Fab")
		)
		(fp_line
			(start -0.12065 -0.3048)
			(end -0.67945 -0.3048)
			(stroke
				(width 0.1)
				(type default)
			)
			(layer "B.Fab")
		)
		(fp_line
			(start -0.12065 -0.2794)
			(end -0.12065 -0.3048)
			(stroke
				(width 0.1)
				(type default)
			)
			(layer "B.Fab")
		)
		(fp_line
			(start -0.120396 0.2794)
			(end 0.12065 0.2794)
			(stroke
				(width 0.1)
				(type default)
			)
			(layer "B.Fab")
		)
		(fp_line
			(start -0.120396 0.3048)
			(end -0.120396 0.2794)
			(stroke
				(width 0.1)
				(type default)
			)
			(layer "B.Fab")
		)
		(fp_line
			(start 0.12065 -0.305054)
			(end 0.12065 -0.2794)
			(stroke
				(width 0.1)
				(type default)
			)
			(layer "B.Fab")
		)
		(fp_line
			(start 0.12065 -0.2794)
			(end -0.12065 -0.2794)
			(stroke
				(width 0.1)
				(type default)
			)
			(layer "B.Fab")
		)
		(fp_line
			(start 0.12065 0.2794)
			(end 0.12065 0.3048)
			(stroke
				(width 0.1)
				(type default)
			)
			(layer "B.Fab")
		)
		(fp_line
			(start 0.12065 0.3048)
			(end 0.67945 0.3048)
			(stroke
				(width 0.1)
				(type default)
			)
			(layer "B.Fab")
		)
		(fp_line
			(start 0.67945 -0.305054)
			(end 0.12065 -0.305054)
			(stroke
				(width 0.1)
				(type default)
			)
			(layer "B.Fab")
		)
		(fp_line
			(start 0.67945 0.3048)
			(end 0.67945 -0.305054)
			(stroke
				(width 0.1)
				(type default)
			)
			(layer "B.Fab")
		)
		(pad "1" smd circle
			(at 0.40005 0 180)
			(size 0 0)
			(layers "B.Cu" "B.Mask" "B.Paste")
			(net "P3V3_9ZXL045_P0_VDD")
		)
		(pad "2" smd circle
			(at -0.40005 0 180)
			(size 0 0)
			(layers "B.Cu" "B.Mask" "B.Paste")
			(net "GND")
		)
	)
	(footprint ""
		(layer "B.Cu")
		(at 134.840218 -42.401998)
		(property "Reference" "C6031"
			(at 0 0 0)
			(layer "B.SilkS")
			(hide yes)
			(effects
				(font
					(size 1.27 1.27)
				)
				(justify mirror)
			)
		)
		(property "Value" ""
			(at 0 0 0)
			(layer "B.Fab")
			(effects
				(font
					(size 1.27 1.27)
				)
				(justify mirror)
			)
		)
		(duplicate_pad_numbers_are_jumpers no)
		(fp_line
			(start -0.7874 -0.4064)
			(end -0.7874 0.4064)
			(stroke
				(width 0.1524)
				(type default)
			)
			(layer "B.SilkS")
		)
		(fp_line
			(start -0.7874 0.4064)
			(end 0.7874 0.4064)
			(stroke
				(width 0.1524)
				(type default)
			)
			(layer "B.SilkS")
		)
		(fp_line
			(start 0.7874 -0.4064)
			(end -0.7874 -0.4064)
			(stroke
				(width 0.1524)
				(type default)
			)
			(layer "B.SilkS")
		)
		(fp_line
			(start 0.7874 0.4064)
			(end 0.7874 -0.4064)
			(stroke
				(width 0.1524)
				(type default)
			)
			(layer "B.SilkS")
		)
		(fp_line
			(start -0.67945 -0.3048)
			(end -0.67945 0.3048)
			(stroke
				(width 0.1)
				(type default)
			)
			(layer "B.Fab")
		)
		(fp_line
			(start -0.67945 0.3048)
			(end -0.120396 0.3048)
			(stroke
				(width 0.1)
				(type default)
			)
			(layer "B.Fab")
		)
		(fp_line
			(start -0.12065 -0.3048)
			(end -0.67945 -0.3048)
			(stroke
				(width 0.1)
				(type default)
			)
			(layer "B.Fab")
		)
		(fp_line
			(start -0.12065 -0.2794)
			(end -0.12065 -0.3048)
			(stroke
				(width 0.1)
				(type default)
			)
			(layer "B.Fab")
		)
		(fp_line
			(start -0.120396 0.2794)
			(end 0.12065 0.2794)
			(stroke
				(width 0.1)
				(type default)
			)
			(layer "B.Fab")
		)
		(fp_line
			(start -0.120396 0.3048)
			(end -0.120396 0.2794)
			(stroke
				(width 0.1)
				(type default)
			)
			(layer "B.Fab")
		)
		(fp_line
			(start 0.12065 -0.305054)
			(end 0.12065 -0.2794)
			(stroke
				(width 0.1)
				(type default)
			)
			(layer "B.Fab")
		)
		(fp_line
			(start 0.12065 -0.2794)
			(end -0.12065 -0.2794)
			(stroke
				(width 0.1)
				(type default)
			)
			(layer "B.Fab")
		)
		(fp_line
			(start 0.12065 0.2794)
			(end 0.12065 0.3048)
			(stroke
				(width 0.1)
				(type default)
			)
			(layer "B.Fab")
		)
		(fp_line
			(start 0.12065 0.3048)
			(end 0.67945 0.3048)
			(stroke
				(width 0.1)
				(type default)
			)
			(layer "B.Fab")
		)
		(fp_line
			(start 0.67945 -0.305054)
			(end 0.12065 -0.305054)
			(stroke
				(width 0.1)
				(type default)
			)
			(layer "B.Fab")
		)
		(fp_line
			(start 0.67945 0.3048)
			(end 0.67945 -0.305054)
			(stroke
				(width 0.1)
				(type default)
			)
			(layer "B.Fab")
		)
		(pad "1" smd circle
			(at 0.40005 0 180)
			(size 0 0)
			(layers "B.Cu" "B.Mask" "B.Paste")
			(net "P1V2_CPU0_USB_DVDD12")
		)
		(pad "2" smd circle
			(at -0.40005 0 180)
			(size 0 0)
			(layers "B.Cu" "B.Mask" "B.Paste")
			(net "GND")
		)
	)
	(footprint ""
		(layer "B.Cu")
		(at 170.307 -98.135948 -90)
		(property "Reference" "R6027"
			(at 0 0 90)
			(layer "B.SilkS")
			(hide yes)
			(effects
				(font
					(size 1.27 1.27)
				)
				(justify mirror)
			)
		)
		(property "Value" ""
			(at 0 0 90)
			(layer "B.Fab")
			(effects
				(font
					(size 1.27 1.27)
				)
				(justify mirror)
			)
		)
		(duplicate_pad_numbers_are_jumpers no)
		(fp_line
			(start -0.7874 0.4064)
			(end 0.7874 0.4064)
			(stroke
				(width 0.1524)
				(type default)
			)
			(layer "B.SilkS")
		)
		(fp_line
			(start 0.7874 0.4064)
			(end 0.7874 -0.4064)
			(stroke
				(width 0.1524)
				(type default)
			)
			(layer "B.SilkS")
		)
		(fp_line
			(start -0.7874 -0.4064)
			(end -0.7874 0.4064)
			(stroke
				(width 0.1524)
				(type default)
			)
			(layer "B.SilkS")
		)
		(fp_line
			(start 0.7874 -0.4064)
			(end -0.7874 -0.4064)
			(stroke
				(width 0.1524)
				(type default)
			)
			(layer "B.SilkS")
		)
		(fp_line
			(start -0.67945 0.3048)
			(end -0.120396 0.3048)
			(stroke
				(width 0.1)
				(type default)
			)
			(layer "B.Fab")
		)
		(fp_line
			(start -0.120396 0.3048)
			(end -0.120396 0.2794)
			(stroke
				(width 0.1)
				(type default)
			)
			(layer "B.Fab")
		)
		(fp_line
			(start 0.12065 0.3048)
			(end 0.67945 0.3048)
			(stroke
				(width 0.1)
				(type default)
			)
			(layer "B.Fab")
		)
		(fp_line
			(start 0.67945 0.3048)
			(end 0.67945 -0.305054)
			(stroke
				(width 0.1)
				(type default)
			)
			(layer "B.Fab")
		)
		(fp_line
			(start -0.120396 0.2794)
			(end 0.12065 0.2794)
			(stroke
				(width 0.1)
				(type default)
			)
			(layer "B.Fab")
		)
		(fp_line
			(start 0.12065 0.2794)
			(end 0.12065 0.3048)
			(stroke
				(width 0.1)
				(type default)
			)
			(layer "B.Fab")
		)
		(fp_line
			(start -0.12065 -0.2794)
			(end -0.12065 -0.3048)
			(stroke
				(width 0.1)
				(type default)
			)
			(layer "B.Fab")
		)
		(fp_line
			(start 0.12065 -0.2794)
			(end -0.12065 -0.2794)
			(stroke
				(width 0.1)
				(type default)
			)
			(layer "B.Fab")
		)
		(fp_line
			(start -0.67945 -0.3048)
			(end -0.67945 0.3048)
			(stroke
				(width 0.1)
				(type default)
			)
			(layer "B.Fab")
		)
		(fp_line
			(start -0.12065 -0.3048)
			(end -0.67945 -0.3048)
			(stroke
				(width 0.1)
				(type default)
			)
			(layer "B.Fab")
		)
		(fp_line
			(start 0.12065 -0.305054)
			(end 0.12065 -0.2794)
			(stroke
				(width 0.1)
				(type default)
			)
			(layer "B.Fab")
		)
		(fp_line
			(start 0.67945 -0.305054)
			(end 0.12065 -0.305054)
			(stroke
				(width 0.1)
				(type default)
			)
			(layer "B.Fab")
		)
		(pad "1" smd circle
			(at 0.40005 0 90)
			(size 0 0)
			(layers "B.Cu" "B.Mask" "B.Paste")
			(net "SGPIO_SCM_RESET_N")
		)
		(pad "2" smd circle
			(at -0.40005 0 90)
			(size 0 0)
			(layers "B.Cu" "B.Mask" "B.Paste")
			(net "GND")
		)
	)
	(footprint ""
		(layer "B.Cu")
		(at 52.364386 -190.821564)
		(property "Reference" "R303"
			(at 0 0 0)
			(layer "B.SilkS")
			(hide yes)
			(effects
				(font
					(size 1.27 1.27)
				)
				(justify mirror)
			)
		)
		(property "Value" ""
			(at 0 0 0)
			(layer "B.Fab")
			(effects
				(font
					(size 1.27 1.27)
				)
				(justify mirror)
			)
		)
		(duplicate_pad_numbers_are_jumpers no)
		(fp_line
			(start -0.7874 -0.4064)
			(end -0.7874 0.4064)
			(stroke
				(width 0.1524)
				(type default)
			)
			(layer "B.SilkS")
		)
		(fp_line
			(start -0.7874 0.4064)
			(end 0.7874 0.4064)
			(stroke
				(width 0.1524)
				(type default)
			)
			(layer "B.SilkS")
		)
		(fp_line
			(start 0.7874 -0.4064)
			(end -0.7874 -0.4064)
			(stroke
				(width 0.1524)
				(type default)
			)
			(layer "B.SilkS")
		)
		(fp_line
			(start 0.7874 0.4064)
			(end 0.7874 -0.4064)
			(stroke
				(width 0.1524)
				(type default)
			)
			(layer "B.SilkS")
		)
		(fp_line
			(start -0.67945 -0.3048)
			(end -0.67945 0.3048)
			(stroke
				(width 0.1)
				(type default)
			)
			(layer "B.Fab")
		)
		(fp_line
			(start -0.67945 0.3048)
			(end -0.120396 0.3048)
			(stroke
				(width 0.1)
				(type default)
			)
			(layer "B.Fab")
		)
		(fp_line
			(start -0.12065 -0.3048)
			(end -0.67945 -0.3048)
			(stroke
				(width 0.1)
				(type default)
			)
			(layer "B.Fab")
		)
		(fp_line
			(start -0.12065 -0.2794)
			(end -0.12065 -0.3048)
			(stroke
				(width 0.1)
				(type default)
			)
			(layer "B.Fab")
		)
		(fp_line
			(start -0.120396 0.2794)
			(end 0.12065 0.2794)
			(stroke
				(width 0.1)
				(type default)
			)
			(layer "B.Fab")
		)
		(fp_line
			(start -0.120396 0.3048)
			(end -0.120396 0.2794)
			(stroke
				(width 0.1)
				(type default)
			)
			(layer "B.Fab")
		)
		(fp_line
			(start 0.12065 -0.305054)
			(end 0.12065 -0.2794)
			(stroke
				(width 0.1)
				(type default)
			)
			(layer "B.Fab")
		)
		(fp_line
			(start 0.12065 -0.2794)
			(end -0.12065 -0.2794)
			(stroke
				(width 0.1)
				(type default)
			)
			(layer "B.Fab")
		)
		(fp_line
			(start 0.12065 0.2794)
			(end 0.12065 0.3048)
			(stroke
				(width 0.1)
				(type default)
			)
			(layer "B.Fab")
		)
		(fp_line
			(start 0.12065 0.3048)
			(end 0.67945 0.3048)
			(stroke
				(width 0.1)
				(type default)
			)
			(layer "B.Fab")
		)
		(fp_line
			(start 0.67945 -0.305054)
			(end 0.12065 -0.305054)
			(stroke
				(width 0.1)
				(type default)
			)
			(layer "B.Fab")
		)
		(fp_line
			(start 0.67945 0.3048)
			(end 0.67945 -0.305054)
			(stroke
				(width 0.1)
				(type default)
			)
			(layer "B.Fab")
		)
		(pad "1" smd circle
			(at 0.40005 0 180)
			(size 0 0)
			(layers "B.Cu" "B.Mask" "B.Paste")
			(net "PWRGD_CHA_CPU1_DIMM0")
		)
		(pad "2" smd circle
			(at -0.40005 0 180)
			(size 0 0)
			(layers "B.Cu" "B.Mask" "B.Paste")
			(net "PWRGD_CHAF_CPU1")
		)
	)
	(footprint ""
		(layer "B.Cu")
		(at 363.088936 -174.01794 90)
		(property "Reference" "PC483_1"
			(at 0 0 90)
			(layer "B.SilkS")
			(hide yes)
			(effects
				(font
					(size 1.27 1.27)
				)
				(justify mirror)
			)
		)
		(property "Value" ""
			(at 0 0 90)
			(layer "B.Fab")
			(effects
				(font
					(size 1.27 1.27)
				)
				(justify mirror)
			)
		)
		(duplicate_pad_numbers_are_jumpers no)
		(fp_line
			(start 1.524 -0.762)
			(end -1.524 -0.762)
			(stroke
				(width 0.1524)
				(type default)
			)
			(layer "B.SilkS")
		)
		(fp_line
			(start -1.524 -0.762)
			(end -1.524 0.762)
			(stroke
				(width 0.1524)
				(type default)
			)
			(layer "B.SilkS")
		)
		(fp_line
			(start 1.524 0.762)
			(end 1.524 -0.762)
			(stroke
				(width 0.1524)
				(type default)
			)
			(layer "B.SilkS")
		)
		(fp_line
			(start -1.524 0.762)
			(end 1.524 0.762)
			(stroke
				(width 0.1524)
				(type default)
			)
			(layer "B.SilkS")
		)
		(fp_line
			(start 1.1049 -0.724916)
			(end 1.1049 0.724916)
			(stroke
				(width 0.1)
				(type default)
			)
			(layer "B.Fab")
		)
		(fp_line
			(start -1.1049 -0.724916)
			(end 1.1049 -0.724916)
			(stroke
				(width 0.1)
				(type default)
			)
			(layer "B.Fab")
		)
		(fp_line
			(start 1.1049 0.724916)
			(end -1.1049 0.724916)
			(stroke
				(width 0.1)
				(type default)
			)
			(layer "B.Fab")
		)
		(fp_line
			(start -1.1049 0.724916)
			(end -1.1049 -0.724916)
			(stroke
				(width 0.1)
				(type default)
			)
			(layer "B.Fab")
		)
		(pad "1" smd rect
			(at 0.889 0 90)
			(size 1.016 1.27)
			(layers "B.Cu" "B.Mask" "B.Paste")
			(net "SW_P12V_AUX_PVDDCR_CPU0_P0_FLT")
		)
		(pad "2" smd rect
			(at -0.889 0 90)
			(size 1.016 1.27)
			(layers "B.Cu" "B.Mask" "B.Paste")
			(net "GND")
		)
	)
	(footprint ""
		(layer "B.Cu")
		(at 134.517384 -387.768592 180)
		(property "Reference" "C481"
			(at 0 0 0)
			(layer "B.SilkS")
			(hide yes)
			(effects
				(font
					(size 1.27 1.27)
				)
				(justify mirror)
			)
		)
		(property "Value" ""
			(at 0 0 0)
			(layer "B.Fab")
			(effects
				(font
					(size 1.27 1.27)
				)
				(justify mirror)
			)
		)
		(duplicate_pad_numbers_are_jumpers no)
		(fp_line
			(start 0.299974 0.150114)
			(end 0.299974 -0.150114)
			(stroke
				(width 0.1)
				(type default)
			)
			(layer "B.Fab")
		)
		(fp_line
			(start 0.299974 -0.150114)
			(end -0.299974 -0.150114)
			(stroke
				(width 0.1)
				(type default)
			)
			(layer "B.Fab")
		)
		(fp_line
			(start -0.299974 0.150114)
			(end 0.299974 0.150114)
			(stroke
				(width 0.1)
				(type default)
			)
			(layer "B.Fab")
		)
		(fp_line
			(start -0.299974 -0.150114)
			(end -0.299974 0.150114)
			(stroke
				(width 0.1)
				(type default)
			)
			(layer "B.Fab")
		)
		(pad "1" smd rect
			(at 0.2667 0)
			(size 0.3048 0.381)
			(layers "B.Cu" "B.Mask" "B.Paste")
			(net "P0V9_CPU1_RT3_2A")
		)
		(pad "2" smd rect
			(at -0.2667 0)
			(size 0.3048 0.381)
			(layers "B.Cu" "B.Mask" "B.Paste")
			(net "GND")
		)
	)
)
